# S9S_MB_2U (Grand Teton) — schematic netlist excerpt (pin names and nets, part order shuffled) for the footprints in the layout excerpt that follows; sources: Cadence DE-HDL packaged netlist, KiCad conversion of 03242023_DA0F0TMBIJ0_F0T_Motherboard_J_brd_V01_OCP.brd

R1253  Q_RES  1K 1% CHIP  pkg 0402LF  page 204 : A = PGPPA_AUX ; B = IRQ_LPC_PIRQA_N_ESPI_ALERT0_N
C1534  Q_CAP_DIFFBUS  DIFF BUS_0.22UF 6.3V 20% X6S  pkg C0201  page 177 : \1\ = P5E_CPU1_PE3_TX_C_DN<6> ; \2\ = P5E_CPU1_PE3_TX_DN<6>
C1177  Q_CAP  1UF 25V 10% X6S  pkg C0402  page 201 : A = RST_RTCRST_N ; B = GND

(kicad_pcb
	(version 20260206)
	(generator "pcbnew")
	(generator_version "10.0")
	(general
		(thickness 1.6)
		(legacy_teardrops no)
	)
	(paper "A4")
	(title_block
		(title "03242023_DA0F0TMBIJ0_F0T_Motherboard_J_brd_V01_OCP.brd")
		(comment 1 "Grand Teton / footprints 2657-2659 of 6105")
	)
	(layers
		(0 "F.Cu" signal "TOP")
		(4 "In1.Cu" signal "GND")
		(6 "In2.Cu" signal "IN1")
		(8 "In3.Cu" signal "GND1")
		(10 "In4.Cu" signal "IN2")
		(12 "In5.Cu" signal "GND2")
		(14 "In6.Cu" signal "IN3")
		(16 "In7.Cu" signal "GND3")
		(18 "In8.Cu" signal "VCC")
		(20 "In9.Cu" signal "VCC1")
		(22 "In10.Cu" signal "GND4")
		(24 "In11.Cu" signal "IN4")
		(26 "In12.Cu" signal "GND5")
		(28 "In13.Cu" signal "IN5")
		(30 "In14.Cu" signal "GND6")
		(32 "In15.Cu" signal "IN6")
		(34 "In16.Cu" signal "GND7")
		(2 "B.Cu" signal "BOTTOM")
		(9 "F.Adhes" user "F.Adhesive")
		(11 "B.Adhes" user "B.Adhesive")
		(13 "F.Paste" user "Package Geometry/Pastemask Top")
		(15 "B.Paste" user "Package Geometry/Pastemask Bottom")
		(5 "F.SilkS" user "Ref Des/Silkscreen Top")
		(7 "B.SilkS" user "Ref Des/Silkscreen Bottom")
		(1 "F.Mask" user "Board Geometry/Soldermask Top")
		(3 "B.Mask" user "Board Geometry/Soldermask Bottom")
		(17 "Dwgs.User" user "User.Drawings")
		(19 "Cmts.User" user "User.Comments")
		(21 "Eco1.User" user "User.Eco1")
		(23 "Eco2.User" user "User.Eco2")
		(25 "Edge.Cuts" user "Board Geometry/Outline")
		(27 "Margin" user)
		(31 "F.CrtYd" user "Package Geometry/Place Bound Top")
		(29 "B.CrtYd" user "Package Geometry/Place Bound Bottom")
		(35 "F.Fab" user "Ref Des/Assembly Top")
		(33 "B.Fab" user "Ref Des/Assembly Bottom")
	)
	(footprint ""
		(layer "F.Cu")
		(at 337.792314 -24.212042 -90)
		(property "Reference" "R1253"
			(at 0 0 270)
			(layer "F.SilkS")
			(hide yes)
			(effects
				(font
					(size 1.27 1.27)
				)
			)
		)
		(property "Value" ""
			(at 0 0 270)
			(layer "F.Fab")
			(effects
				(font
					(size 1.27 1.27)
				)
			)
		)
		(duplicate_pad_numbers_are_jumpers no)
		(fp_line
			(start -0.7874 0.4064)
			(end -0.7874 -0.4064)
			(stroke
				(width 0.1524)
				(type default)
			)
			(layer "F.SilkS")
		)
		(fp_line
			(start 0.7874 0.4064)
			(end -0.7874 0.4064)
			(stroke
				(width 0.1524)
				(type default)
			)
			(layer "F.SilkS")
		)
		(fp_line
			(start -0.7874 -0.4064)
			(end 0.7874 -0.4064)
			(stroke
				(width 0.1524)
				(type default)
			)
			(layer "F.SilkS")
		)
		(fp_line
			(start 0.7874 -0.4064)
			(end 0.7874 0.4064)
			(stroke
				(width 0.1524)
				(type default)
			)
			(layer "F.SilkS")
		)
		(fp_line
			(start -0.67945 0.3048)
			(end -0.67945 -0.305054)
			(stroke
				(width 0.1)
				(type default)
			)
			(layer "F.Fab")
		)
		(fp_line
			(start -0.12065 0.3048)
			(end -0.67945 0.3048)
			(stroke
				(width 0.1)
				(type default)
			)
			(layer "F.Fab")
		)
		(fp_line
			(start 0.120396 0.3048)
			(end 0.120396 0.2794)
			(stroke
				(width 0.1)
				(type default)
			)
			(layer "F.Fab")
		)
		(fp_line
			(start 0.67945 0.3048)
			(end 0.120396 0.3048)
			(stroke
				(width 0.1)
				(type default)
			)
			(layer "F.Fab")
		)
		(fp_line
			(start -0.12065 0.2794)
			(end -0.12065 0.3048)
			(stroke
				(width 0.1)
				(type default)
			)
			(layer "F.Fab")
		)
		(fp_line
			(start 0.120396 0.2794)
			(end -0.12065 0.2794)
			(stroke
				(width 0.1)
				(type default)
			)
			(layer "F.Fab")
		)
		(fp_line
			(start -0.12065 -0.2794)
			(end 0.12065 -0.2794)
			(stroke
				(width 0.1)
				(type default)
			)
			(layer "F.Fab")
		)
		(fp_line
			(start 0.12065 -0.2794)
			(end 0.12065 -0.3048)
			(stroke
				(width 0.1)
				(type default)
			)
			(layer "F.Fab")
		)
		(fp_line
			(start 0.12065 -0.3048)
			(end 0.67945 -0.3048)
			(stroke
				(width 0.1)
				(type default)
			)
			(layer "F.Fab")
		)
		(fp_line
			(start 0.67945 -0.3048)
			(end 0.67945 0.3048)
			(stroke
				(width 0.1)
				(type default)
			)
			(layer "F.Fab")
		)
		(fp_line
			(start -0.67945 -0.305054)
			(end -0.12065 -0.305054)
			(stroke
				(width 0.1)
				(type default)
			)
			(layer "F.Fab")
		)
		(fp_line
			(start -0.12065 -0.305054)
			(end -0.12065 -0.2794)
			(stroke
				(width 0.1)
				(type default)
			)
			(layer "F.Fab")
		)
		(pad "1" smd circle
			(at -0.40005 0 270)
			(size 0 0)
			(layers "F.Cu" "F.Mask" "F.Paste")
			(net "PGPPA_AUX")
		)
		(pad "2" smd circle
			(at 0.40005 0 270)
			(size 0 0)
			(layers "F.Cu" "F.Mask" "F.Paste")
			(net "IRQ_LPC_PIRQA_N_ESPI_ALERT0_N")
		)
	)
	(footprint ""
		(layer "F.Cu")
		(at 149.044914 -408.517344 -90)
		(property "Reference" "C1534"
			(at 0 0 270)
			(layer "F.SilkS")
			(hide yes)
			(effects
				(font
					(size 1.27 1.27)
				)
			)
		)
		(property "Value" ""
			(at 0 0 270)
			(layer "F.Fab")
			(effects
				(font
					(size 1.27 1.27)
				)
			)
		)
		(duplicate_pad_numbers_are_jumpers no)
		(fp_line
			(start -0.299974 0.150114)
			(end -0.299974 -0.150114)
			(stroke
				(width 0.1)
				(type default)
			)
			(layer "F.Fab")
		)
		(fp_line
			(start 0.299974 0.150114)
			(end -0.299974 0.150114)
			(stroke
				(width 0.1)
				(type default)
			)
			(layer "F.Fab")
		)
		(fp_line
			(start -0.299974 -0.150114)
			(end 0.299974 -0.150114)
			(stroke
				(width 0.1)
				(type default)
			)
			(layer "F.Fab")
		)
		(fp_line
			(start 0.299974 -0.150114)
			(end 0.299974 0.150114)
			(stroke
				(width 0.1)
				(type default)
			)
			(layer "F.Fab")
		)
		(pad "1" smd rect
			(at -0.2667 0 270)
			(size 0.3048 0.381)
			(layers "F.Cu" "F.Mask" "F.Paste")
			(net "P5E_CPU1_PE3_TX_C_DN<6>")
		)
		(pad "2" smd rect
			(at 0.2667 0 270)
			(size 0.3048 0.381)
			(layers "F.Cu" "F.Mask" "F.Paste")
			(net "P5E_CPU1_PE3_TX_DN<6>")
		)
	)
	(footprint ""
		(layer "F.Cu")
		(at 303.600612 -34.937446 -90)
		(property "Reference" "C1177"
			(at 0 0 270)
			(layer "F.SilkS")
			(hide yes)
			(effects
				(font
					(size 1.27 1.27)
				)
			)
		)
		(property "Value" ""
			(at 0 0 270)
			(layer "F.Fab")
			(effects
				(font
					(size 1.27 1.27)
				)
			)
		)
		(duplicate_pad_numbers_are_jumpers no)
		(fp_line
			(start -0.7874 0.4064)
			(end -0.7874 -0.4064)
			(stroke
				(width 0.1524)
				(type default)
			)
			(layer "F.SilkS")
		)
		(fp_line
			(start 0.7874 0.4064)
			(end -0.7874 0.4064)
			(stroke
				(width 0.1524)
				(type default)
			)
			(layer "F.SilkS")
		)
		(fp_line
			(start -0.7874 -0.4064)
			(end 0.7874 -0.4064)
			(stroke
				(width 0.1524)
				(type default)
			)
			(layer "F.SilkS")
		)
		(fp_line
			(start 0.7874 -0.4064)
			(end 0.7874 0.4064)
			(stroke
				(width 0.1524)
				(type default)
			)
			(layer "F.SilkS")
		)
		(fp_line
			(start -0.67945 0.3048)
			(end -0.67945 -0.305054)
			(stroke
				(width 0.1)
				(type default)
			)
			(layer "F.Fab")
		)
		(fp_line
			(start -0.12065 0.3048)
			(end -0.67945 0.3048)
			(stroke
				(width 0.1)
				(type default)
			)
			(layer "F.Fab")
		)
		(fp_line
			(start 0.120396 0.3048)
			(end 0.120396 0.2794)
			(stroke
				(width 0.1)
				(type default)
			)
			(layer "F.Fab")
		)
		(fp_line
			(start 0.67945 0.3048)
			(end 0.120396 0.3048)
			(stroke
				(width 0.1)
				(type default)
			)
			(layer "F.Fab")
		)
		(fp_line
			(start -0.12065 0.2794)
			(end -0.12065 0.3048)
			(stroke
				(width 0.1)
				(type default)
			)
			(layer "F.Fab")
		)
		(fp_line
			(start 0.120396 0.2794)
			(end -0.12065 0.2794)
			(stroke
				(width 0.1)
				(type default)
			)
			(layer "F.Fab")
		)
		(fp_line
			(start -0.12065 -0.2794)
			(end 0.12065 -0.2794)
			(stroke
				(width 0.1)
				(type default)
			)
			(layer "F.Fab")
		)
		(fp_line
			(start 0.12065 -0.2794)
			(end 0.12065 -0.3048)
			(stroke
				(width 0.1)
				(type default)
			)
			(layer "F.Fab")
		)
		(fp_line
			(start 0.12065 -0.3048)
			(end 0.67945 -0.3048)
			(stroke
				(width 0.1)
				(type default)
			)
			(layer "F.Fab")
		)
		(fp_line
			(start 0.67945 -0.3048)
			(end 0.67945 0.3048)
			(stroke
				(width 0.1)
				(type default)
			)
			(layer "F.Fab")
		)
		(fp_line
			(start -0.67945 -0.305054)
			(end -0.12065 -0.305054)
			(stroke
				(width 0.1)
				(type default)
			)
			(layer "F.Fab")
		)
		(fp_line
			(start -0.12065 -0.305054)
			(end -0.12065 -0.2794)
			(stroke
				(width 0.1)
				(type default)
			)
			(layer "F.Fab")
		)
		(pad "1" smd circle
			(at -0.40005 0 270)
			(size 0 0)
			(layers "F.Cu" "F.Mask" "F.Paste")
			(net "RST_RTCRST_N")
		)
		(pad "2" smd circle
			(at 0.40005 0 270)
			(size 0 0)
			(layers "F.Cu" "F.Mask" "F.Paste")
			(net "GND")
		)
	)
)
